# S9S_MB_2U (Grand Teton) — schematic netlist excerpt (pin names and nets, part order shuffled) for the footprints in the layout excerpt that follows; sources: Cadence DE-HDL packaged netlist, KiCad conversion of 03242023_DA0F0TMBIJ0_F0T_Motherboard_J_brd_V01_OCP.brd

R3653  Q_RES  680 1% CHIP  pkg 0402LF  page 152 : A = USB_HUB_RREF ; B = GND
C249  Q_CAP  10UF 6.3V 20% X6S  pkg C0402  page 77 : A = PVCCIN_CPU1 ; B = GND

(kicad_pcb
	(version 20260206)
	(generator "pcbnew")
	(generator_version "10.0")
	(general
		(thickness 1.6)
		(legacy_teardrops no)
	)
	(paper "A4")
	(title_block
		(title "03242023_DA0F0TMBIJ0_F0T_Motherboard_J_brd_V01_OCP.brd")
		(comment 1 "Grand Teton / footprints 1288-1289 of 6105")
	)
	(layers
		(0 "F.Cu" signal "TOP")
		(4 "In1.Cu" signal "GND")
		(6 "In2.Cu" signal "IN1")
		(8 "In3.Cu" signal "GND1")
		(10 "In4.Cu" signal "IN2")
		(12 "In5.Cu" signal "GND2")
		(14 "In6.Cu" signal "IN3")
		(16 "In7.Cu" signal "GND3")
		(18 "In8.Cu" signal "VCC")
		(20 "In9.Cu" signal "VCC1")
		(22 "In10.Cu" signal "GND4")
		(24 "In11.Cu" signal "IN4")
		(26 "In12.Cu" signal "GND5")
		(28 "In13.Cu" signal "IN5")
		(30 "In14.Cu" signal "GND6")
		(32 "In15.Cu" signal "IN6")
		(34 "In16.Cu" signal "GND7")
		(2 "B.Cu" signal "BOTTOM")
		(9 "F.Adhes" user "F.Adhesive")
		(11 "B.Adhes" user "B.Adhesive")
		(13 "F.Paste" user "Package Geometry/Pastemask Top")
		(15 "B.Paste" user "Package Geometry/Pastemask Bottom")
		(5 "F.SilkS" user "Ref Des/Silkscreen Top")
		(7 "B.SilkS" user "Ref Des/Silkscreen Bottom")
		(1 "F.Mask" user "Board Geometry/Soldermask Top")
		(3 "B.Mask" user "Board Geometry/Soldermask Bottom")
		(17 "Dwgs.User" user "User.Drawings")
		(19 "Cmts.User" user "User.Comments")
		(21 "Eco1.User" user "User.Eco1")
		(23 "Eco2.User" user "User.Eco2")
		(25 "Edge.Cuts" user "Board Geometry/Outline")
		(27 "Margin" user)
		(31 "F.CrtYd" user "Package Geometry/Place Bound Top")
		(29 "B.CrtYd" user "Package Geometry/Place Bound Bottom")
		(35 "F.Fab" user "Ref Des/Assembly Top")
		(33 "B.Fab" user "Ref Des/Assembly Bottom")
	)
	(footprint ""
		(layer "F.Cu")
		(at 118.542816 -247.715278 90)
		(property "Reference" "C249"
			(at 0 0 90)
			(layer "F.SilkS")
			(hide yes)
			(effects
				(font
					(size 1.27 1.27)
				)
			)
		)
		(property "Value" ""
			(at 0 0 90)
			(layer "F.Fab")
			(effects
				(font
					(size 1.27 1.27)
				)
			)
		)
		(duplicate_pad_numbers_are_jumpers no)
		(fp_line
			(start 0.7874 -0.4064)
			(end 0.7874 0.4064)
			(stroke
				(width 0.1524)
				(type default)
			)
			(layer "F.SilkS")
		)
		(fp_line
			(start -0.7874 -0.4064)
			(end 0.7874 -0.4064)
			(stroke
				(width 0.1524)
				(type default)
			)
			(layer "F.SilkS")
		)
		(fp_line
			(start 0.7874 0.4064)
			(end -0.7874 0.4064)
			(stroke
				(width 0.1524)
				(type default)
			)
			(layer "F.SilkS")
		)
		(fp_line
			(start -0.7874 0.4064)
			(end -0.7874 -0.4064)
			(stroke
				(width 0.1524)
				(type default)
			)
			(layer "F.SilkS")
		)
		(fp_line
			(start -0.12065 -0.305054)
			(end -0.12065 -0.2794)
			(stroke
				(width 0.1)
				(type default)
			)
			(layer "F.Fab")
		)
		(fp_line
			(start -0.67945 -0.305054)
			(end -0.12065 -0.305054)
			(stroke
				(width 0.1)
				(type default)
			)
			(layer "F.Fab")
		)
		(fp_line
			(start 0.67945 -0.3048)
			(end 0.67945 0.3048)
			(stroke
				(width 0.1)
				(type default)
			)
			(layer "F.Fab")
		)
		(fp_line
			(start 0.12065 -0.3048)
			(end 0.67945 -0.3048)
			(stroke
				(width 0.1)
				(type default)
			)
			(layer "F.Fab")
		)
		(fp_line
			(start 0.12065 -0.2794)
			(end 0.12065 -0.3048)
			(stroke
				(width 0.1)
				(type default)
			)
			(layer "F.Fab")
		)
		(fp_line
			(start -0.12065 -0.2794)
			(end 0.12065 -0.2794)
			(stroke
				(width 0.1)
				(type default)
			)
			(layer "F.Fab")
		)
		(fp_line
			(start 0.120396 0.2794)
			(end -0.12065 0.2794)
			(stroke
				(width 0.1)
				(type default)
			)
			(layer "F.Fab")
		)
		(fp_line
			(start -0.12065 0.2794)
			(end -0.12065 0.3048)
			(stroke
				(width 0.1)
				(type default)
			)
			(layer "F.Fab")
		)
		(fp_line
			(start 0.67945 0.3048)
			(end 0.120396 0.3048)
			(stroke
				(width 0.1)
				(type default)
			)
			(layer "F.Fab")
		)
		(fp_line
			(start 0.120396 0.3048)
			(end 0.120396 0.2794)
			(stroke
				(width 0.1)
				(type default)
			)
			(layer "F.Fab")
		)
		(fp_line
			(start -0.12065 0.3048)
			(end -0.67945 0.3048)
			(stroke
				(width 0.1)
				(type default)
			)
			(layer "F.Fab")
		)
		(fp_line
			(start -0.67945 0.3048)
			(end -0.67945 -0.305054)
			(stroke
				(width 0.1)
				(type default)
			)
			(layer "F.Fab")
		)
		(pad "1" smd circle
			(at -0.40005 0 90)
			(size 0 0)
			(layers "F.Cu" "F.Mask" "F.Paste")
			(net "PVCCIN_CPU1")
		)
		(pad "2" smd circle
			(at 0.40005 0 90)
			(size 0 0)
			(layers "F.Cu" "F.Mask" "F.Paste")
			(net "GND")
		)
	)
	(footprint ""
		(layer "F.Cu")
		(at 8.75919 -101.854 180)
		(property "Reference" "R3653"
			(at 0 0 180)
			(layer "F.SilkS")
			(hide yes)
			(effects
				(font
					(size 1.27 1.27)
				)
			)
		)
		(property "Value" ""
			(at 0 0 180)
			(layer "F.Fab")
			(effects
				(font
					(size 1.27 1.27)
				)
			)
		)
		(duplicate_pad_numbers_are_jumpers no)
		(fp_line
			(start 0.7874 0.4064)
			(end -0.7874 0.4064)
			(stroke
				(width 0.1524)
				(type default)
			)
			(layer "F.SilkS")
		)
		(fp_line
			(start 0.7874 -0.4064)
			(end 0.7874 0.4064)
			(stroke
				(width 0.1524)
				(type default)
			)
			(layer "F.SilkS")
		)
		(fp_line
			(start -0.7874 0.4064)
			(end -0.7874 -0.4064)
			(stroke
				(width 0.1524)
				(type default)
			)
			(layer "F.SilkS")
		)
		(fp_line
			(start -0.7874 -0.4064)
			(end 0.7874 -0.4064)
			(stroke
				(width 0.1524)
				(type default)
			)
			(layer "F.SilkS")
		)
		(fp_line
			(start 0.67945 0.3048)
			(end 0.120396 0.3048)
			(stroke
				(width 0.1)
				(type default)
			)
			(layer "F.Fab")
		)
		(fp_line
			(start 0.67945 -0.3048)
			(end 0.67945 0.3048)
			(stroke
				(width 0.1)
				(type default)
			)
			(layer "F.Fab")
		)
		(fp_line
			(start 0.12065 -0.2794)
			(end 0.12065 -0.3048)
			(stroke
				(width 0.1)
				(type default)
			)
			(layer "F.Fab")
		)
		(fp_line
			(start 0.12065 -0.3048)
			(end 0.67945 -0.3048)
			(stroke
				(width 0.1)
				(type default)
			)
			(layer "F.Fab")
		)
		(fp_line
			(start 0.120396 0.3048)
			(end 0.120396 0.2794)
			(stroke
				(width 0.1)
				(type default)
			)
			(layer "F.Fab")
		)
		(fp_line
			(start 0.120396 0.2794)
			(end -0.12065 0.2794)
			(stroke
				(width 0.1)
				(type default)
			)
			(layer "F.Fab")
		)
		(fp_line
			(start -0.12065 0.3048)
			(end -0.67945 0.3048)
			(stroke
				(width 0.1)
				(type default)
			)
			(layer "F.Fab")
		)
		(fp_line
			(start -0.12065 0.2794)
			(end -0.12065 0.3048)
			(stroke
				(width 0.1)
				(type default)
			)
			(layer "F.Fab")
		)
		(fp_line
			(start -0.12065 -0.2794)
			(end 0.12065 -0.2794)
			(stroke
				(width 0.1)
				(type default)
			)
			(layer "F.Fab")
		)
		(fp_line
			(start -0.12065 -0.305054)
			(end -0.12065 -0.2794)
			(stroke
				(width 0.1)
				(type default)
			)
			(layer "F.Fab")
		)
		(fp_line
			(start -0.67945 0.3048)
			(end -0.67945 -0.305054)
			(stroke
				(width 0.1)
				(type default)
			)
			(layer "F.Fab")
		)
		(fp_line
			(start -0.67945 -0.305054)
			(end -0.12065 -0.305054)
			(stroke
				(width 0.1)
				(type default)
			)
			(layer "F.Fab")
		)
		(pad "1" smd circle
			(at -0.40005 0 180)
			(size 0 0)
			(layers "F.Cu" "F.Mask" "F.Paste")
			(net "USB_HUB_RREF")
		)
		(pad "2" smd circle
			(at 0.40005 0 180)
			(size 0 0)
			(layers "F.Cu" "F.Mask" "F.Paste")
			(net "GND")
		)
	)
)
